(kicad_pcb
	(version 20260206)
	(generator "pcbnew")
	(generator_version "10.0")
	(general
		(thickness 1.6)
		(legacy_teardrops no)
	)
	(paper "A4")
	(title_block
		(title "04192023_DAF0TMB3IC0_F0TG_MB_C_brd_V02_OCP.brd")
		(comment 1 "Grand Teton / footprints 2700-2706 of 8354")
	)
	(layers
		(0 "F.Cu" signal "TOP")
		(4 "In1.Cu" signal "GND")
		(6 "In2.Cu" signal "IN1")
		(8 "In3.Cu" signal "GND1")
		(10 "In4.Cu" signal "IN2")
		(12 "In5.Cu" signal "GND2")
		(14 "In6.Cu" signal "IN3")
		(16 "In7.Cu" signal "GND3")
		(18 "In8.Cu" signal "VCC")
		(20 "In9.Cu" signal "VCC1")
		(22 "In10.Cu" signal "GND4")
		(24 "In11.Cu" signal "IN4")
		(26 "In12.Cu" signal "GND5")
		(28 "In13.Cu" signal "IN5")
		(30 "In14.Cu" signal "GND6")
		(32 "In15.Cu" signal "IN6")
		(34 "In16.Cu" signal "GND7")
		(2 "B.Cu" signal "BOTTOM")
		(9 "F.Adhes" user "F.Adhesive")
		(11 "B.Adhes" user "B.Adhesive")
		(13 "F.Paste" user "Package Geometry/Pastemask Top")
		(15 "B.Paste" user "Package Geometry/Pastemask Bottom")
		(5 "F.SilkS" user "Ref Des/Silkscreen Top")
		(7 "B.SilkS" user "Ref Des/Silkscreen Bottom")
		(1 "F.Mask" user "Board Geometry/Soldermask Top")
		(3 "B.Mask" user "Board Geometry/Soldermask Bottom")
		(17 "Dwgs.User" user "User.Drawings")
		(19 "Cmts.User" user "User.Comments")
		(21 "Eco1.User" user "User.Eco1")
		(23 "Eco2.User" user "User.Eco2")
		(25 "Edge.Cuts" user "Board Geometry/Outline")
		(27 "Margin" user)
		(31 "F.CrtYd" user "Package Geometry/Place Bound Top")
		(29 "B.CrtYd" user "Package Geometry/Place Bound Bottom")
		(35 "F.Fab" user "Ref Des/Assembly Top")
		(33 "B.Fab" user "Ref Des/Assembly Bottom")
	)
	(footprint ""
		(layer "F.Cu")
		(at 35.65144 -108.09732 -90)
		(property "Reference" "R1007"
			(at 0 0 270)
			(layer "F.SilkS")
			(hide yes)
			(effects
				(font
					(size 1.27 1.27)
				)
			)
		)
		(property "Value" ""
			(at 0 0 270)
			(layer "F.Fab")
			(effects
				(font
					(size 1.27 1.27)
				)
			)
		)
		(duplicate_pad_numbers_are_jumpers no)
		(fp_line
			(start -0.7874 0.4064)
			(end -0.7874 -0.4064)
			(stroke
				(width 0.1524)
				(type default)
			)
			(layer "F.SilkS")
		)
		(fp_line
			(start 0.7874 0.4064)
			(end -0.7874 0.4064)
			(stroke
				(width 0.1524)
				(type default)
			)
			(layer "F.SilkS")
		)
		(fp_line
			(start -0.7874 -0.4064)
			(end 0.7874 -0.4064)
			(stroke
				(width 0.1524)
				(type default)
			)
			(layer "F.SilkS")
		)
		(fp_line
			(start 0.7874 -0.4064)
			(end 0.7874 0.4064)
			(stroke
				(width 0.1524)
				(type default)
			)
			(layer "F.SilkS")
		)
		(fp_line
			(start -0.67945 0.3048)
			(end -0.67945 -0.305054)
			(stroke
				(width 0.1)
				(type default)
			)
			(layer "F.Fab")
		)
		(fp_line
			(start -0.12065 0.3048)
			(end -0.67945 0.3048)
			(stroke
				(width 0.1)
				(type default)
			)
			(layer "F.Fab")
		)
		(fp_line
			(start 0.120396 0.3048)
			(end 0.120396 0.2794)
			(stroke
				(width 0.1)
				(type default)
			)
			(layer "F.Fab")
		)
		(fp_line
			(start 0.67945 0.3048)
			(end 0.120396 0.3048)
			(stroke
				(width 0.1)
				(type default)
			)
			(layer "F.Fab")
		)
		(fp_line
			(start -0.12065 0.2794)
			(end -0.12065 0.3048)
			(stroke
				(width 0.1)
				(type default)
			)
			(layer "F.Fab")
		)
		(fp_line
			(start 0.120396 0.2794)
			(end -0.12065 0.2794)
			(stroke
				(width 0.1)
				(type default)
			)
			(layer "F.Fab")
		)
		(fp_line
			(start -0.12065 -0.2794)
			(end 0.12065 -0.2794)
			(stroke
				(width 0.1)
				(type default)
			)
			(layer "F.Fab")
		)
		(fp_line
			(start 0.12065 -0.2794)
			(end 0.12065 -0.3048)
			(stroke
				(width 0.1)
				(type default)
			)
			(layer "F.Fab")
		)
		(fp_line
			(start 0.12065 -0.3048)
			(end 0.67945 -0.3048)
			(stroke
				(width 0.1)
				(type default)
			)
			(layer "F.Fab")
		)
		(fp_line
			(start 0.67945 -0.3048)
			(end 0.67945 0.3048)
			(stroke
				(width 0.1)
				(type default)
			)
			(layer "F.Fab")
		)
		(fp_line
			(start -0.67945 -0.305054)
			(end -0.12065 -0.305054)
			(stroke
				(width 0.1)
				(type default)
			)
			(layer "F.Fab")
		)
		(fp_line
			(start -0.12065 -0.305054)
			(end -0.12065 -0.2794)
			(stroke
				(width 0.1)
				(type default)
			)
			(layer "F.Fab")
		)
		(pad "1" smd circle
			(at -0.40005 0 270)
			(size 0 0)
			(layers "F.Cu" "F.Mask" "F.Paste")
			(net "P12V_AUX")
		)
		(pad "2" smd circle
			(at 0.40005 0 270)
			(size 0 0)
			(layers "F.Cu" "F.Mask" "F.Paste")
			(net "P12V_AUX_DSC_G1")
		)
	)
	(footprint ""
		(layer "F.Cu")
		(at 419.76294 -101.270308 90)
		(property "Reference" "PR3846"
			(at 0 0 90)
			(layer "F.SilkS")
			(hide yes)
			(effects
				(font
					(size 1.27 1.27)
				)
			)
		)
		(property "Value" ""
			(at 0 0 90)
			(layer "F.Fab")
			(effects
				(font
					(size 1.27 1.27)
				)
			)
		)
		(duplicate_pad_numbers_are_jumpers no)
		(fp_line
			(start 0.7874 -0.4064)
			(end 0.7874 0.4064)
			(stroke
				(width 0.1524)
				(type default)
			)
			(layer "F.SilkS")
		)
		(fp_line
			(start -0.7874 -0.4064)
			(end 0.7874 -0.4064)
			(stroke
				(width 0.1524)
				(type default)
			)
			(layer "F.SilkS")
		)
		(fp_line
			(start 0.7874 0.4064)
			(end -0.7874 0.4064)
			(stroke
				(width 0.1524)
				(type default)
			)
			(layer "F.SilkS")
		)
		(fp_line
			(start -0.7874 0.4064)
			(end -0.7874 -0.4064)
			(stroke
				(width 0.1524)
				(type default)
			)
			(layer "F.SilkS")
		)
		(fp_line
			(start -0.12065 -0.305054)
			(end -0.12065 -0.2794)
			(stroke
				(width 0.1)
				(type default)
			)
			(layer "F.Fab")
		)
		(fp_line
			(start -0.67945 -0.305054)
			(end -0.12065 -0.305054)
			(stroke
				(width 0.1)
				(type default)
			)
			(layer "F.Fab")
		)
		(fp_line
			(start 0.67945 -0.3048)
			(end 0.67945 0.3048)
			(stroke
				(width 0.1)
				(type default)
			)
			(layer "F.Fab")
		)
		(fp_line
			(start 0.12065 -0.3048)
			(end 0.67945 -0.3048)
			(stroke
				(width 0.1)
				(type default)
			)
			(layer "F.Fab")
		)
		(fp_line
			(start 0.12065 -0.2794)
			(end 0.12065 -0.3048)
			(stroke
				(width 0.1)
				(type default)
			)
			(layer "F.Fab")
		)
		(fp_line
			(start -0.12065 -0.2794)
			(end 0.12065 -0.2794)
			(stroke
				(width 0.1)
				(type default)
			)
			(layer "F.Fab")
		)
		(fp_line
			(start 0.120396 0.2794)
			(end -0.12065 0.2794)
			(stroke
				(width 0.1)
				(type default)
			)
			(layer "F.Fab")
		)
		(fp_line
			(start -0.12065 0.2794)
			(end -0.12065 0.3048)
			(stroke
				(width 0.1)
				(type default)
			)
			(layer "F.Fab")
		)
		(fp_line
			(start 0.67945 0.3048)
			(end 0.120396 0.3048)
			(stroke
				(width 0.1)
				(type default)
			)
			(layer "F.Fab")
		)
		(fp_line
			(start 0.120396 0.3048)
			(end 0.120396 0.2794)
			(stroke
				(width 0.1)
				(type default)
			)
			(layer "F.Fab")
		)
		(fp_line
			(start -0.12065 0.3048)
			(end -0.67945 0.3048)
			(stroke
				(width 0.1)
				(type default)
			)
			(layer "F.Fab")
		)
		(fp_line
			(start -0.67945 0.3048)
			(end -0.67945 -0.305054)
			(stroke
				(width 0.1)
				(type default)
			)
			(layer "F.Fab")
		)
		(pad "1" smd circle
			(at -0.40005 0 90)
			(size 0 0)
			(layers "F.Cu" "F.Mask" "F.Paste")
			(net "GND")
		)
		(pad "2" smd circle
			(at 0.40005 0 90)
			(size 0 0)
			(layers "F.Cu" "F.Mask" "F.Paste")
			(net "P3V3_OCP_ILIMIT_1")
		)
	)
	(footprint ""
		(layer "F.Cu")
		(at 200.98512 -332.612238 -90)
		(property "Reference" "PL72"
			(at -0.763524 -4.20243 90)
			(unlocked yes)
			(layer "F.SilkS")
			(effects
				(font
					(size 0.7874 0.5842)
					(thickness 0.1524)
				)
				(justify left)
			)
		)
		(property "Value" ""
			(at 0 0 270)
			(layer "F.Fab")
			(effects
				(font
					(size 1.27 1.27)
				)
			)
		)
		(duplicate_pad_numbers_are_jumpers no)
		(fp_line
			(start -3.64998 3.350006)
			(end -3.64998 1.8288)
			(stroke
				(width 0.1524)
				(type default)
			)
			(layer "F.SilkS")
		)
		(fp_line
			(start 3.64998 3.350006)
			(end -3.64998 3.350006)
			(stroke
				(width 0.1524)
				(type default)
			)
			(layer "F.SilkS")
		)
		(fp_line
			(start 3.64998 1.8034)
			(end 3.64998 3.350006)
			(stroke
				(width 0.1524)
				(type default)
			)
			(layer "F.SilkS")
		)
		(fp_line
			(start -3.64998 -1.8034)
			(end -3.64998 -3.350006)
			(stroke
				(width 0.1524)
				(type default)
			)
			(layer "F.SilkS")
		)
		(fp_line
			(start -3.6576 -3.350006)
			(end 3.64998 -3.350006)
			(stroke
				(width 0.1524)
				(type default)
			)
			(layer "F.SilkS")
		)
		(fp_line
			(start 3.64998 -3.350006)
			(end 3.64998 -1.8034)
			(stroke
				(width 0.1524)
				(type default)
			)
			(layer "F.SilkS")
		)
		(fp_line
			(start -3.64998 3.350006)
			(end -3.64998 -3.350006)
			(stroke
				(width 0.1)
				(type default)
			)
			(layer "F.Fab")
		)
		(fp_line
			(start 3.64998 3.350006)
			(end -3.64998 3.350006)
			(stroke
				(width 0.1)
				(type default)
			)
			(layer "F.Fab")
		)
		(fp_line
			(start -3.64998 -3.350006)
			(end 3.64998 -3.350006)
			(stroke
				(width 0.1)
				(type default)
			)
			(layer "F.Fab")
		)
		(fp_line
			(start 3.64998 -3.350006)
			(end 3.64998 3.350006)
			(stroke
				(width 0.1)
				(type default)
			)
			(layer "F.Fab")
		)
		(pad "1" smd rect
			(at -2.92481 0 270)
			(size 2.15392 3.302)
			(layers "F.Cu" "F.Mask" "F.Paste")
			(net "SW_PVDD_33_S5_SW")
		)
		(pad "2" smd rect
			(at 2.92481 0 270)
			(size 2.15392 3.302)
			(layers "F.Cu" "F.Mask" "F.Paste")
			(net "PVDD_33_S5")
		)
	)
	(footprint ""
		(layer "F.Cu")
		(at 435.621176 -103.77043 90)
		(property "Reference" "PC2144"
			(at 0 0 90)
			(layer "F.SilkS")
			(hide yes)
			(effects
				(font
					(size 1.27 1.27)
				)
			)
		)
		(property "Value" ""
			(at 0 0 90)
			(layer "F.Fab")
			(effects
				(font
					(size 1.27 1.27)
				)
			)
		)
		(duplicate_pad_numbers_are_jumpers no)
		(fp_line
			(start 0.7874 -0.4064)
			(end 0.7874 0.4064)
			(stroke
				(width 0.1524)
				(type default)
			)
			(layer "F.SilkS")
		)
		(fp_line
			(start -0.7874 -0.4064)
			(end 0.7874 -0.4064)
			(stroke
				(width 0.1524)
				(type default)
			)
			(layer "F.SilkS")
		)
		(fp_line
			(start 0.7874 0.4064)
			(end -0.7874 0.4064)
			(stroke
				(width 0.1524)
				(type default)
			)
			(layer "F.SilkS")
		)
		(fp_line
			(start -0.7874 0.4064)
			(end -0.7874 -0.4064)
			(stroke
				(width 0.1524)
				(type default)
			)
			(layer "F.SilkS")
		)
		(fp_line
			(start -0.12065 -0.305054)
			(end -0.12065 -0.2794)
			(stroke
				(width 0.1)
				(type default)
			)
			(layer "F.Fab")
		)
		(fp_line
			(start -0.67945 -0.305054)
			(end -0.12065 -0.305054)
			(stroke
				(width 0.1)
				(type default)
			)
			(layer "F.Fab")
		)
		(fp_line
			(start 0.67945 -0.3048)
			(end 0.67945 0.3048)
			(stroke
				(width 0.1)
				(type default)
			)
			(layer "F.Fab")
		)
		(fp_line
			(start 0.12065 -0.3048)
			(end 0.67945 -0.3048)
			(stroke
				(width 0.1)
				(type default)
			)
			(layer "F.Fab")
		)
		(fp_line
			(start 0.12065 -0.2794)
			(end 0.12065 -0.3048)
			(stroke
				(width 0.1)
				(type default)
			)
			(layer "F.Fab")
		)
		(fp_line
			(start -0.12065 -0.2794)
			(end 0.12065 -0.2794)
			(stroke
				(width 0.1)
				(type default)
			)
			(layer "F.Fab")
		)
		(fp_line
			(start 0.120396 0.2794)
			(end -0.12065 0.2794)
			(stroke
				(width 0.1)
				(type default)
			)
			(layer "F.Fab")
		)
		(fp_line
			(start -0.12065 0.2794)
			(end -0.12065 0.3048)
			(stroke
				(width 0.1)
				(type default)
			)
			(layer "F.Fab")
		)
		(fp_line
			(start 0.67945 0.3048)
			(end 0.120396 0.3048)
			(stroke
				(width 0.1)
				(type default)
			)
			(layer "F.Fab")
		)
		(fp_line
			(start 0.120396 0.3048)
			(end 0.120396 0.2794)
			(stroke
				(width 0.1)
				(type default)
			)
			(layer "F.Fab")
		)
		(fp_line
			(start -0.12065 0.3048)
			(end -0.67945 0.3048)
			(stroke
				(width 0.1)
				(type default)
			)
			(layer "F.Fab")
		)
		(fp_line
			(start -0.67945 0.3048)
			(end -0.67945 -0.305054)
			(stroke
				(width 0.1)
				(type default)
			)
			(layer "F.Fab")
		)
		(pad "1" smd circle
			(at -0.40005 0 90)
			(size 0 0)
			(layers "F.Cu" "F.Mask" "F.Paste")
			(net "P3V3_OCP_SFF_R")
		)
		(pad "2" smd circle
			(at 0.40005 0 90)
			(size 0 0)
			(layers "F.Cu" "F.Mask" "F.Paste")
			(net "P3V3_OCP_GATE_PU202_1")
		)
	)
	(footprint ""
		(layer "F.Cu")
		(at 111.133128 -179.906168 -90)
		(property "Reference" "PR523"
			(at 0 0 270)
			(layer "F.SilkS")
			(hide yes)
			(effects
				(font
					(size 1.27 1.27)
				)
			)
		)
		(property "Value" ""
			(at 0 0 270)
			(layer "F.Fab")
			(effects
				(font
					(size 1.27 1.27)
				)
			)
		)
		(duplicate_pad_numbers_are_jumpers no)
		(fp_line
			(start -0.7874 0.4064)
			(end -0.7874 -0.4064)
			(stroke
				(width 0.1524)
				(type default)
			)
			(layer "F.SilkS")
		)
		(fp_line
			(start 0.7874 0.4064)
			(end -0.7874 0.4064)
			(stroke
				(width 0.1524)
				(type default)
			)
			(layer "F.SilkS")
		)
		(fp_line
			(start -0.7874 -0.4064)
			(end 0.7874 -0.4064)
			(stroke
				(width 0.1524)
				(type default)
			)
			(layer "F.SilkS")
		)
		(fp_line
			(start 0.7874 -0.4064)
			(end 0.7874 0.4064)
			(stroke
				(width 0.1524)
				(type default)
			)
			(layer "F.SilkS")
		)
		(fp_line
			(start -0.67945 0.3048)
			(end -0.67945 -0.305054)
			(stroke
				(width 0.1)
				(type default)
			)
			(layer "F.Fab")
		)
		(fp_line
			(start -0.12065 0.3048)
			(end -0.67945 0.3048)
			(stroke
				(width 0.1)
				(type default)
			)
			(layer "F.Fab")
		)
		(fp_line
			(start 0.120396 0.3048)
			(end 0.120396 0.2794)
			(stroke
				(width 0.1)
				(type default)
			)
			(layer "F.Fab")
		)
		(fp_line
			(start 0.67945 0.3048)
			(end 0.120396 0.3048)
			(stroke
				(width 0.1)
				(type default)
			)
			(layer "F.Fab")
		)
		(fp_line
			(start -0.12065 0.2794)
			(end -0.12065 0.3048)
			(stroke
				(width 0.1)
				(type default)
			)
			(layer "F.Fab")
		)
		(fp_line
			(start 0.120396 0.2794)
			(end -0.12065 0.2794)
			(stroke
				(width 0.1)
				(type default)
			)
			(layer "F.Fab")
		)
		(fp_line
			(start -0.12065 -0.2794)
			(end 0.12065 -0.2794)
			(stroke
				(width 0.1)
				(type default)
			)
			(layer "F.Fab")
		)
		(fp_line
			(start 0.12065 -0.2794)
			(end 0.12065 -0.3048)
			(stroke
				(width 0.1)
				(type default)
			)
			(layer "F.Fab")
		)
		(fp_line
			(start 0.12065 -0.3048)
			(end 0.67945 -0.3048)
			(stroke
				(width 0.1)
				(type default)
			)
			(layer "F.Fab")
		)
		(fp_line
			(start 0.67945 -0.3048)
			(end 0.67945 0.3048)
			(stroke
				(width 0.1)
				(type default)
			)
			(layer "F.Fab")
		)
		(fp_line
			(start -0.67945 -0.305054)
			(end -0.12065 -0.305054)
			(stroke
				(width 0.1)
				(type default)
			)
			(layer "F.Fab")
		)
		(fp_line
			(start -0.12065 -0.305054)
			(end -0.12065 -0.2794)
			(stroke
				(width 0.1)
				(type default)
			)
			(layer "F.Fab")
		)
		(pad "1" smd circle
			(at -0.40005 0 270)
			(size 0 0)
			(layers "F.Cu" "F.Mask" "F.Paste")
			(net "SW_PVDDCR_CPU0_P1_SW4_RC")
		)
		(pad "2" smd circle
			(at 0.40005 0 270)
			(size 0 0)
			(layers "F.Cu" "F.Mask" "F.Paste")
			(net "GND")
		)
	)
	(footprint ""
		(layer "F.Cu")
		(at 361.22229 -395.1732 90)
		(property "Reference" "R1016"
			(at 0 0 90)
			(layer "F.SilkS")
			(hide yes)
			(effects
				(font
					(size 1.27 1.27)
				)
			)
		)
		(property "Value" ""
			(at 0 0 90)
			(layer "F.Fab")
			(effects
				(font
					(size 1.27 1.27)
				)
			)
		)
		(duplicate_pad_numbers_are_jumpers no)
		(fp_line
			(start 0.32512 -0.175006)
			(end 0.32512 0.175006)
			(stroke
				(width 0.1)
				(type default)
			)
			(layer "F.Fab")
		)
		(fp_line
			(start -0.32512 -0.175006)
			(end 0.32512 -0.175006)
			(stroke
				(width 0.1)
				(type default)
			)
			(layer "F.Fab")
		)
		(fp_line
			(start 0.32512 0.175006)
			(end -0.32512 0.175006)
			(stroke
				(width 0.1)
				(type default)
			)
			(layer "F.Fab")
		)
		(fp_line
			(start -0.32512 0.175006)
			(end -0.32512 -0.175006)
			(stroke
				(width 0.1)
				(type default)
			)
			(layer "F.Fab")
		)
		(pad "1" smd rect
			(at -0.2667 0 90)
			(size 0.3048 0.381)
			(layers "F.Cu" "F.Mask" "F.Paste")
			(net "RT_CPU0_P1_ADDR2")
		)
		(pad "2" smd rect
			(at 0.2667 0 270)
			(size 0.3048 0.381)
			(layers "F.Cu" "F.Mask" "F.Paste")
			(net "GND")
		)
	)
	(footprint ""
		(layer "F.Cu")
		(at 96.058736 -119.469154 -90)
		(property "Reference" "R1363"
			(at 0 0 270)
			(layer "F.SilkS")
			(hide yes)
			(effects
				(font
					(size 1.27 1.27)
				)
			)
		)
		(property "Value" ""
			(at 0 0 270)
			(layer "F.Fab")
			(effects
				(font
					(size 1.27 1.27)
				)
			)
		)
		(duplicate_pad_numbers_are_jumpers no)
		(fp_line
			(start -0.7874 0.4064)
			(end -0.7874 -0.4064)
			(stroke
				(width 0.1524)
				(type default)
			)
			(layer "F.SilkS")
		)
		(fp_line
			(start 0.7874 0.4064)
			(end -0.7874 0.4064)
			(stroke
				(width 0.1524)
				(type default)
			)
			(layer "F.SilkS")
		)
		(fp_line
			(start -0.7874 -0.4064)
			(end 0.7874 -0.4064)
			(stroke
				(width 0.1524)
				(type default)
			)
			(layer "F.SilkS")
		)
		(fp_line
			(start 0.7874 -0.4064)
			(end 0.7874 0.4064)
			(stroke
				(width 0.1524)
				(type default)
			)
			(layer "F.SilkS")
		)
		(fp_line
			(start -0.67945 0.3048)
			(end -0.67945 -0.305054)
			(stroke
				(width 0.1)
				(type default)
			)
			(layer "F.Fab")
		)
		(fp_line
			(start -0.12065 0.3048)
			(end -0.67945 0.3048)
			(stroke
				(width 0.1)
				(type default)
			)
			(layer "F.Fab")
		)
		(fp_line
			(start 0.120396 0.3048)
			(end 0.120396 0.2794)
			(stroke
				(width 0.1)
				(type default)
			)
			(layer "F.Fab")
		)
		(fp_line
			(start 0.67945 0.3048)
			(end 0.120396 0.3048)
			(stroke
				(width 0.1)
				(type default)
			)
			(layer "F.Fab")
		)
		(fp_line
			(start -0.12065 0.2794)
			(end -0.12065 0.3048)
			(stroke
				(width 0.1)
				(type default)
			)
			(layer "F.Fab")
		)
		(fp_line
			(start 0.120396 0.2794)
			(end -0.12065 0.2794)
			(stroke
				(width 0.1)
				(type default)
			)
			(layer "F.Fab")
		)
		(fp_line
			(start -0.12065 -0.2794)
			(end 0.12065 -0.2794)
			(stroke
				(width 0.1)
				(type default)
			)
			(layer "F.Fab")
		)
		(fp_line
			(start 0.12065 -0.2794)
			(end 0.12065 -0.3048)
			(stroke
				(width 0.1)
				(type default)
			)
			(layer "F.Fab")
		)
		(fp_line
			(start 0.12065 -0.3048)
			(end 0.67945 -0.3048)
			(stroke
				(width 0.1)
				(type default)
			)
			(layer "F.Fab")
		)
		(fp_line
			(start 0.67945 -0.3048)
			(end 0.67945 0.3048)
			(stroke
				(width 0.1)
				(type default)
			)
			(layer "F.Fab")
		)
		(fp_line
			(start -0.67945 -0.305054)
			(end -0.12065 -0.305054)
			(stroke
				(width 0.1)
				(type default)
			)
			(layer "F.Fab")
		)
		(fp_line
			(start -0.12065 -0.305054)
			(end -0.12065 -0.2794)
			(stroke
				(width 0.1)
				(type default)
			)
			(layer "F.Fab")
		)
		(pad "1" smd circle
			(at -0.40005 0 270)
			(size 0 0)
			(layers "F.Cu" "F.Mask" "F.Paste")
			(net "PWRGD_P12V_MEM")
		)
		(pad "2" smd circle
			(at 0.40005 0 270)
			(size 0 0)
			(layers "F.Cu" "F.Mask" "F.Paste")
			(net "PWRGD_P12V_MEM_R")
		)
	)
)
